(kicad_pcb
	(version 20241229)
	(generator "pcbnew")
	(generator_version "9.0")
	(general
		(thickness 1.552)
		(legacy_teardrops no)
	)
	(paper "A4")
	(title_block
		(date "2023-07-25")
		(rev "1.1.4")
		(comment 9 "footprints 240-243 of 379")
	)
	(layers
		(0 "F.Cu" signal)
		(4 "In1.Cu" signal)
		(6 "In2.Cu" signal)
		(8 "In3.Cu" signal)
		(10 "In4.Cu" signal)
		(12 "In5.Cu" signal)
		(14 "In6.Cu" signal)
		(2 "B.Cu" signal)
		(9 "F.Adhes" user "F.Adhesive")
		(11 "B.Adhes" user "B.Adhesive")
		(13 "F.Paste" user)
		(15 "B.Paste" user)
		(5 "F.SilkS" user "F.Silkscreen")
		(7 "B.SilkS" user "B.Silkscreen")
		(1 "F.Mask" user)
		(3 "B.Mask" user)
		(17 "Dwgs.User" user "User.Drawings")
		(19 "Cmts.User" user "User.Comments")
		(21 "Eco1.User" user "User.Eco1")
		(23 "Eco2.User" user "User.Eco2")
		(25 "Edge.Cuts" user)
		(27 "Margin" user)
		(31 "F.CrtYd" user "F.Courtyard")
		(29 "B.CrtYd" user "B.Courtyard")
		(35 "F.Fab" user)
		(33 "B.Fab" user)
	)
	(footprint "antmicro-footprints:TSSOP-16_4.4x5mm_P0.65mm"
		(layer "F.Cu")
		(at 105.79 103.1)
		(property "Reference" "U17"
			(at -6.16 -1.96 0)
			(layer "F.SilkS")
			(effects
				(font
					(size 0.65 0.65)
					(thickness 0.15)
				)
				(justify left bottom)
			)
		)
		(property "Value" "SC18IS602BIPW"
			(at 0 3.749 0)
			(layer "F.Fab")
			(hide yes)
			(effects
				(font
					(size 0.7 0.7)
					(thickness 0.15)
				)
				(justify left bottom)
			)
		)
		(property "Datasheet" "https://www.nxp.com/docs/en/data-sheet/SC18IS602B.pdf"
			(at 0 0 0)
			(layer "F.Fab")
			(hide yes)
			(effects
				(font
					(size 1.27 1.27)
					(thickness 0.15)
				)
			)
		)
		(property "Description" "I²C Controller SPI Interface 16-TSSOP"
			(at 0 0 0)
			(layer "F.Fab")
			(hide yes)
			(effects
				(font
					(size 1.27 1.27)
					(thickness 0.15)
				)
			)
		)
		(property "Author" "Antmicro"
			(at 0 0 0)
			(layer "F.Fab")
			(hide yes)
			(effects
				(font
					(size 1 1)
					(thickness 0.15)
				)
			)
		)
		(property "License" "Apache-2.0"
			(at 0 0 0)
			(layer "F.Fab")
			(hide yes)
			(effects
				(font
					(size 1 1)
					(thickness 0.15)
				)
			)
		)
		(property "MPN" "SC18IS602BIPW"
			(at 0 0 0)
			(layer "F.Fab")
			(hide yes)
			(effects
				(font
					(size 1 1)
					(thickness 0.15)
				)
			)
		)
		(property "Manufacturer" "NXP"
			(at 0 0 0)
			(layer "F.Fab")
			(hide yes)
			(effects
				(font
					(size 1 1)
					(thickness 0.15)
				)
			)
		)
		(sheetname "/FPGA/")
		(sheetfile "fpga.kicad_sch")
		(attr smd)
		(fp_line
			(start -2.149 -2.735)
			(end 2.25 -2.735)
			(stroke
				(width 0.15)
				(type solid)
			)
			(layer "F.SilkS")
		)
		(fp_line
			(start 0.051 2.733)
			(end -2.149 2.733)
			(stroke
				(width 0.15)
				(type solid)
			)
			(layer "F.SilkS")
		)
		(fp_line
			(start 0.051 2.733)
			(end 2.25 2.733)
			(stroke
				(width 0.15)
				(type solid)
			)
			(layer "F.SilkS")
		)
		(fp_circle
			(center -2.81 -2.62)
			(end -2.76 -2.62)
			(stroke
				(width 0.15)
				(type solid)
			)
			(fill yes)
			(layer "F.SilkS")
		)
		(fp_line
			(start -3.81 -2.75)
			(end -3.81 2.74)
			(stroke
				(width 0.05)
				(type solid)
			)
			(layer "F.CrtYd")
		)
		(fp_line
			(start -3.81 2.74)
			(end 3.89 2.74)
			(stroke
				(width 0.05)
				(type solid)
			)
			(layer "F.CrtYd")
		)
		(fp_line
			(start 3.89 -2.75)
			(end -3.81 -2.75)
			(stroke
				(width 0.05)
				(type solid)
			)
			(layer "F.CrtYd")
		)
		(fp_line
			(start 3.89 2.74)
			(end 3.89 -2.75)
			(stroke
				(width 0.05)
				(type solid)
			)
			(layer "F.CrtYd")
		)
		(fp_line
			(start -2.149 -1.5)
			(end -1.15 -2.5)
			(stroke
				(width 0.15)
				(type solid)
			)
			(layer "F.Fab")
		)
		(fp_line
			(start -2.149 2.499)
			(end -2.149 -1.5)
			(stroke
				(width 0.15)
				(type solid)
			)
			(layer "F.Fab")
		)
		(fp_line
			(start -1.15 -2.5)
			(end 2.25 -2.5)
			(stroke
				(width 0.15)
				(type solid)
			)
			(layer "F.Fab")
		)
		(fp_line
			(start 2.25 -2.5)
			(end 2.25 2.499)
			(stroke
				(width 0.15)
				(type solid)
			)
			(layer "F.Fab")
		)
		(fp_line
			(start 2.25 2.499)
			(end -2.149 2.499)
			(stroke
				(width 0.15)
				(type solid)
			)
			(layer "F.Fab")
		)
		(fp_text user "${REFERENCE}"
			(at -3.81 8.149 0)
			(layer "F.Fab")
			(effects
				(font
					(size 0.7 0.7)
					(thickness 0.15)
				)
				(justify left bottom)
			)
		)
		(fp_text user "License: Apache-2.0"
			(at -3.81 5.749 0)
			(layer "F.Fab")
			(effects
				(font
					(size 0.7 0.7)
					(thickness 0.15)
				)
				(justify left bottom)
			)
		)
		(fp_text user "Author: Antmicro"
			(at -3.81 6.949 0)
			(layer "F.Fab")
			(effects
				(font
					(size 0.7 0.7)
					(thickness 0.15)
				)
				(justify left bottom)
			)
		)
		(pad "1" smd rect
			(at -2.815 -2.275)
			(size 1.475 0.4)
			(layers "F.Cu" "F.Mask" "F.Paste")
			(net 29 "/FPGA/~{FLASH_CS_SOFT}")
			(pinfunction "GPIO0/~{SS0}")
			(pintype "bidirectional")
		)
		(pad "2" smd rect
			(at -2.815 -1.625)
			(size 1.475 0.4)
			(layers "F.Cu" "F.Mask" "F.Paste")
			(net 376 "/FPGA/SEL")
			(pinfunction "GPIO1/~{SS1}")
			(pintype "bidirectional")
		)
		(pad "3" smd rect
			(at -2.815 -0.975)
			(size 1.475 0.4)
			(layers "F.Cu" "F.Mask" "F.Paste")
			(net 299 "Net-(U17-~{RESET})")
			(pinfunction "~{RESET}")
			(pintype "input")
		)
		(pad "4" smd rect
			(at -2.815 -0.325)
			(size 1.475 0.4)
			(layers "F.Cu" "F.Mask" "F.Paste")
			(net 1 "GND")
			(pinfunction "V_{SS}")
			(pintype "power_in")
		)
		(pad "5" smd rect
			(at -2.815 0.325)
			(size 1.475 0.4)
			(layers "F.Cu" "F.Mask" "F.Paste")
			(net 31 "/FPGA/MISO_SOFT")
			(pinfunction "MISO")
			(pintype "input")
		)
		(pad "6" smd rect
			(at -2.815 0.975)
			(size 1.475 0.4)
			(layers "F.Cu" "F.Mask" "F.Paste")
			(net 32 "/FPGA/MOSI_SOFT")
			(pinfunction "MOSI")
			(pintype "output")
		)
		(pad "7" smd rect
			(at -2.815 1.625)
			(size 1.475 0.4)
			(layers "F.Cu" "F.Mask" "F.Paste")
			(net 290 "Net-(U17-SDA)")
			(pinfunction "SDA")
			(pintype "bidirectional")
		)
		(pad "8" smd rect
			(at -2.815 2.275)
			(size 1.475 0.4)
			(layers "F.Cu" "F.Mask" "F.Paste")
			(net 298 "Net-(U17-SCL)")
			(pinfunction "SCL")
			(pintype "input")
		)
		(pad "9" smd rect
			(at 2.91 2.275)
			(size 1.475 0.4)
			(layers "F.Cu" "F.Mask" "F.Paste")
			(net 309 "Net-(U17-~{INT})")
			(pinfunction "~{INT}")
			(pintype "output")
		)
		(pad "10" smd rect
			(at 2.91 1.625)
			(size 1.475 0.4)
			(layers "F.Cu" "F.Mask" "F.Paste")
			(net 358 "Net-(U17-GPIO2{slash}~{SS2})")
			(pinfunction "GPIO2/~{SS2}")
			(pintype "bidirectional")
		)
		(pad "11" smd rect
			(at 2.91 0.975)
			(size 1.475 0.4)
			(layers "F.Cu" "F.Mask" "F.Paste")
			(net 33 "/FPGA/SPI_CLK_SOFT")
			(pinfunction "SCLK")
			(pintype "output")
		)
		(pad "12" smd rect
			(at 2.91 0.325)
			(size 1.475 0.4)
			(layers "F.Cu" "F.Mask" "F.Paste")
			(net 2 "+3V3")
			(pinfunction "V_{DD}")
			(pintype "power_in")
		)
		(pad "13" smd rect
			(at 2.91 -0.325)
			(size 1.475 0.4)
			(layers "F.Cu" "F.Mask" "F.Paste")
			(net 372 "Net-(U17-GPIO3{slash}~{SS3})")
			(pinfunction "GPIO3/~{SS3}")
			(pintype "bidirectional")
		)
		(pad "14" smd rect
			(at 2.91 -0.975)
			(size 1.475 0.4)
			(layers "F.Cu" "F.Mask" "F.Paste")
			(net 330 "Net-(U17-A0)")
			(pinfunction "A0")
			(pintype "input")
		)
		(pad "15" smd rect
			(at 2.91 -1.625)
			(size 1.475 0.4)
			(layers "F.Cu" "F.Mask" "F.Paste")
			(net 316 "Net-(U17-A1)")
			(pinfunction "A1")
			(pintype "input")
		)
		(pad "16" smd rect
			(at 2.91 -2.275)
			(size 1.475 0.4)
			(layers "F.Cu" "F.Mask" "F.Paste")
			(net 308 "Net-(U17-A2)")
			(pinfunction "A2")
			(pintype "input")
		)
	)
	(footprint "antmicro-footprints:R_0402_1005Metric"
		(layer "F.Cu")
		(at 139.53 59.34 -90)
		(descr "Resistor SMD 0402")
		(tags "resistor SMD 0402")
		(property "Reference" "R10"
			(at 1.1 0.7 270)
			(layer "F.SilkS")
			(effects
				(font
					(size 0.65 0.65)
					(thickness 0.15)
				)
				(justify left bottom)
			)
		)
		(property "Value" "R_1k3_0402"
			(at 0 1.4 270)
			(layer "F.Fab")
			(hide yes)
			(effects
				(font
					(size 0.7 0.7)
					(thickness 0.15)
				)
				(justify left bottom)
			)
		)
		(property "Datasheet" "https://www.bourns.com/docs/product-datasheets/cr.pdf"
			(at 0 0 270)
			(layer "F.Fab")
			(hide yes)
			(effects
				(font
					(size 1.27 1.27)
					(thickness 0.15)
				)
			)
		)
		(property "Description" "SMD Chip Resistor, 1.3 kohm, ± 1%, 62.5 mW, 0402 [1005 Metric], Thick Film, General Purpose"
			(at 0 0 270)
			(layer "F.Fab")
			(hide yes)
			(effects
				(font
					(size 1.27 1.27)
					(thickness 0.15)
				)
			)
		)
		(property "Author" "Antmicro"
			(at 80.19 198.87 0)
			(layer "F.Fab")
			(hide yes)
			(effects
				(font
					(size 1 1)
					(thickness 0.15)
				)
			)
		)
		(property "License" "Apache-2.0"
			(at 80.19 198.87 0)
			(layer "F.Fab")
			(hide yes)
			(effects
				(font
					(size 1 1)
					(thickness 0.15)
				)
			)
		)
		(property "MPN" "CR0402-FX-1301GLF"
			(at 80.19 198.87 0)
			(layer "F.Fab")
			(hide yes)
			(effects
				(font
					(size 1 1)
					(thickness 0.15)
				)
			)
		)
		(property "Manufacturer" "Bourns"
			(at 80.19 198.87 0)
			(layer "F.Fab")
			(hide yes)
			(effects
				(font
					(size 1 1)
					(thickness 0.15)
				)
			)
		)
		(property "Tolerance" "1%"
			(at 80.19 198.87 0)
			(layer "F.Fab")
			(hide yes)
			(effects
				(font
					(size 1 1)
					(thickness 0.15)
				)
			)
		)
		(property "Val" "1k3"
			(at 80.19 198.87 0)
			(layer "F.Fab")
			(hide yes)
			(effects
				(font
					(size 1 1)
					(thickness 0.15)
				)
			)
		)
		(sheetname "/Power Supply/")
		(sheetfile "supply.kicad_sch")
		(attr smd)
		(fp_rect
			(start -0.925 -0.47)
			(end 0.925 0.47)
			(stroke
				(width 0.05)
				(type default)
			)
			(fill no)
			(layer "F.CrtYd")
		)
		(fp_rect
			(start -0.5 -0.25)
			(end 0.5 0.25)
			(stroke
				(width 0.15)
				(type solid)
			)
			(fill no)
			(layer "F.Fab")
		)
		(fp_text user "Author: Antmicro"
			(at -0.95 4.169 270)
			(layer "F.Fab")
			(effects
				(font
					(size 0.7 0.7)
					(thickness 0.15)
				)
				(justify left bottom)
			)
		)
		(fp_text user "${REFERENCE}"
			(at -0.95 3.168 270)
			(layer "F.Fab")
			(effects
				(font
					(size 0.7 0.7)
					(thickness 0.15)
				)
				(justify left bottom)
			)
		)
		(fp_text user "License: Apache-2.0"
			(at -0.95 5.169 270)
			(layer "F.Fab")
			(effects
				(font
					(size 0.7 0.7)
					(thickness 0.15)
				)
				(justify left bottom)
			)
		)
		(pad "1" smd roundrect
			(at -0.48 0 270)
			(size 0.59 0.64)
			(layers "F.Cu" "F.Mask" "F.Paste")
			(roundrect_rratio 0.25)
			(net 263 "Net-(U6-FB)")
			(pintype "passive")
		)
		(pad "2" smd roundrect
			(at 0.48 0 270)
			(size 0.59 0.64)
			(layers "F.Cu" "F.Mask" "F.Paste")
			(roundrect_rratio 0.25)
			(net 274 "/Power Supply/1V5_OUT")
			(pintype "passive")
		)
	)
	(footprint "antmicro-footprints:C_0402_1005Metric"
		(layer "F.Cu")
		(at 167.33 64.24 -90)
		(descr "Capacitor SMD 0402")
		(tags "capacitor SMD 0402")
		(property "Reference" "C15"
			(at -1.1 -1.4 90)
			(layer "F.SilkS")
			(effects
				(font
					(size 0.65 0.65)
					(thickness 0.15)
				)
				(justify right bottom)
			)
		)
		(property "Value" "C_100n_0402"
			(at 0 1.4 90)
			(layer "F.Fab")
			(hide yes)
			(effects
				(font
					(size 0.7 0.7)
					(thickness 0.15)
				)
				(justify right bottom)
			)
		)
		(property "Datasheet" "https://www.murata.com/products/productdetail?partno=GRM155R61H104KE14%23"
			(at 0 0 270)
			(layer "F.Fab")
			(hide yes)
			(effects
				(font
					(size 1.27 1.27)
					(thickness 0.15)
				)
			)
		)
		(property "Description" "SMD Multilayer Ceramic Capacitor, 0.1 µF, 50 V, 0402 [1005 Metric], ± 10%, X5R, GRM Series"
			(at 0 0 270)
			(layer "F.Fab")
			(hide yes)
			(effects
				(font
					(size 1.27 1.27)
					(thickness 0.15)
				)
			)
		)
		(property "Author" "Antmicro"
			(at 103.09 231.57 0)
			(layer "F.Fab")
			(hide yes)
			(effects
				(font
					(size 1 1)
					(thickness 0.15)
				)
			)
		)
		(property "Dielectric" "X5R"
			(at 103.09 231.57 0)
			(layer "F.Fab")
			(hide yes)
			(effects
				(font
					(size 1 1)
					(thickness 0.15)
				)
			)
		)
		(property "License" "Apache-2.0"
			(at 103.09 231.57 0)
			(layer "F.Fab")
			(hide yes)
			(effects
				(font
					(size 1 1)
					(thickness 0.15)
				)
			)
		)
		(property "MPN" "GRM155R61H104KE14D"
			(at 103.09 231.57 0)
			(layer "F.Fab")
			(hide yes)
			(effects
				(font
					(size 1 1)
					(thickness 0.15)
				)
			)
		)
		(property "Manufacturer" "Murata"
			(at 103.09 231.57 0)
			(layer "F.Fab")
			(hide yes)
			(effects
				(font
					(size 1 1)
					(thickness 0.15)
				)
			)
		)
		(property "Val" "100n"
			(at 103.09 231.57 0)
			(layer "F.Fab")
			(hide yes)
			(effects
				(font
					(size 1 1)
					(thickness 0.15)
				)
			)
		)
		(property "Voltage" "50V"
			(at 103.09 231.57 0)
			(layer "F.Fab")
			(hide yes)
			(effects
				(font
					(size 1 1)
					(thickness 0.15)
				)
			)
		)
		(sheetname "/Power Supply/")
		(sheetfile "supply.kicad_sch")
		(attr smd)
		(fp_rect
			(start -0.925 -0.47)
			(end 0.925 0.47)
			(stroke
				(width 0.05)
				(type default)
			)
			(fill no)
			(layer "F.CrtYd")
		)
		(fp_line
			(start -0.494 0.248)
			(end -0.494 -0.25)
			(stroke
				(width 0.15)
				(type solid)
			)
			(layer "F.Fab")
		)
		(fp_line
			(start 0.504 0.248)
			(end -0.494 0.248)
			(stroke
				(width 0.15)
				(type solid)
			)
			(layer "F.Fab")
		)
		(fp_line
			(start -0.494 -0.25)
			(end 0.504 -0.25)
			(stroke
				(width 0.15)
				(type solid)
			)
			(layer "F.Fab")
		)
		(fp_line
			(start 0.504 -0.25)
			(end 0.504 0.248)
			(stroke
				(width 0.15)
				(type solid)
			)
			(layer "F.Fab")
		)
		(fp_text user "License: Apache-2.0"
			(at -0.939 5.799 270)
			(layer "F.Fab")
			(effects
				(font
					(size 0.7 0.7)
					(thickness 0.15)
				)
				(justify left bottom)
			)
		)
		(fp_text user "${REFERENCE}"
			(at -0.939 4.599 270)
			(layer "F.Fab")
			(effects
				(font
					(size 0.7 0.7)
					(thickness 0.15)
				)
				(justify left bottom)
			)
		)
		(fp_text user "Author: Antmicro"
			(at -0.939 3.399 270)
			(layer "F.Fab")
			(effects
				(font
					(size 0.7 0.7)
					(thickness 0.15)
				)
				(justify left bottom)
			)
		)
		(pad "1" smd roundrect
			(at -0.48 0 270)
			(size 0.59 0.64)
			(layers "F.Cu" "F.Mask" "F.Paste")
			(roundrect_rratio 0.25)
			(net 278 "/Power Supply/3V3_SW")
			(pintype "passive")
		)
		(pad "2" smd roundrect
			(at 0.48 0 270)
			(size 0.59 0.64)
			(layers "F.Cu" "F.Mask" "F.Paste")
			(roundrect_rratio 0.25)
			(net 140 "Net-(U7-BST)")
			(pintype "passive")
		)
	)
	(footprint "antmicro-footprints:C_0603_1608Metric"
		(layer "B.Cu")
		(at 130.76 101.07)
		(descr "Capacitor SMD 0603")
		(tags "capacitor 0603")
		(property "Reference" "C116"
			(at -1.44 1.76 0)
			(layer "B.SilkS")
			(effects
				(font
					(size 0.65 0.65)
					(thickness 0.15)
				)
				(justify right bottom mirror)
			)
		)
		(property "Value" "C_10u_0603"
			(at 0 -1.6 0)
			(layer "B.Fab")
			(hide yes)
			(effects
				(font
					(size 0.7 0.7)
					(thickness 0.15)
				)
				(justify right bottom mirror)
			)
		)
		(property "Datasheet" "https://www.murata.com/products/productdetail?partno=GRM188R61A106KE69%23"
			(at 0 0 0)
			(layer "F.Fab")
			(hide yes)
			(effects
				(font
					(size 1.27 1.27)
					(thickness 0.15)
				)
			)
		)
		(property "Description" "SMD Multilayer Ceramic Capacitor, 10 µF, 10 V, 0603 [1608 Metric], ± 10%, X5R, GRM Series"
			(at 0 0 0)
			(layer "F.Fab")
			(hide yes)
			(effects
				(font
					(size 1.27 1.27)
					(thickness 0.15)
				)
			)
		)
		(property "Author" "Antmicro"
			(at 0 0 0)
			(layer "B.Fab")
			(hide yes)
			(effects
				(font
					(size 1 1)
					(thickness 0.15)
				)
				(justify mirror)
			)
		)
		(property "License" "Apache-2.0"
			(at 0 0 0)
			(layer "B.Fab")
			(hide yes)
			(effects
				(font
					(size 1 1)
					(thickness 0.15)
				)
				(justify mirror)
			)
		)
		(property "MPN" "GRM188R61A106KE69D"
			(at 0 0 0)
			(layer "B.Fab")
			(hide yes)
			(effects
				(font
					(size 1 1)
					(thickness 0.15)
				)
				(justify mirror)
			)
		)
		(property "Manufacturer" "Murata"
			(at 0 0 0)
			(layer "B.Fab")
			(hide yes)
			(effects
				(font
					(size 1 1)
					(thickness 0.15)
				)
				(justify mirror)
			)
		)
		(property "Val" "10u"
			(at 0 0 0)
			(layer "B.Fab")
			(hide yes)
			(effects
				(font
					(size 1 1)
					(thickness 0.15)
				)
				(justify mirror)
			)
		)
		(property "Voltage" ""
			(at 0 0 0)
			(layer "B.Fab")
			(hide yes)
			(effects
				(font
					(size 1 1)
					(thickness 0.15)
				)
				(justify mirror)
			)
		)
		(property "Dielectric" "template_dielectric"
			(at 0 0 0)
			(unlocked yes)
			(layer "B.Fab")
			(hide yes)
			(effects
				(font
					(size 1 1)
					(thickness 0.15)
				)
				(justify mirror)
			)
		)
		(sheetname "/FPGA Power/")
		(sheetfile "FPGA_Power.kicad_sch")
		(attr smd)
		(fp_line
			(start -0.15 -0.4)
			(end 0.15 -0.4)
			(stroke
				(width 0.15)
				(type solid)
			)
			(layer "B.SilkS")
		)
		(fp_line
			(start -0.15 0.4)
			(end 0.15 0.4)
			(stroke
				(width 0.15)
				(type solid)
			)
			(layer "B.SilkS")
		)
		(fp_rect
			(start -1.25 0.65)
			(end 1.25 -0.65)
			(stroke
				(width 0.05)
				(type solid)
			)
			(fill no)
			(layer "B.CrtYd")
		)
		(fp_rect
			(start -0.8 0.4)
			(end 0.8 -0.4)
			(stroke
				(width 0.15)
				(type solid)
			)
			(fill no)
			(layer "B.Fab")
		)
		(fp_text user "Author: Antmicro"
			(at -1.682 -4.894 180)
			(layer "B.Fab")
			(effects
				(font
					(size 0.7 0.7)
					(thickness 0.15)
				)
				(justify left bottom mirror)
			)
		)
		(fp_text user "${REFERENCE}"
			(at -1.682 -3.895 180)
			(layer "B.Fab")
			(effects
				(font
					(size 0.7 0.7)
					(thickness 0.15)
				)
				(justify left bottom mirror)
			)
		)
		(fp_text user "License: Apache-2.0"
			(at -1.682 -5.895 180)
			(layer "B.Fab")
			(effects
				(font
					(size 0.7 0.7)
					(thickness 0.15)
				)
				(justify left bottom mirror)
			)
		)
		(pad "1" smd roundrect
			(at -0.7 0)
			(size 0.8 1)
			(layers "B.Cu" "B.Mask" "B.Paste")
			(roundrect_rratio 0.2)
			(net 1 "GND")
			(pintype "passive")
		)
		(pad "2" smd roundrect
			(at 0.7 0)
			(size 0.8 1)
			(layers "B.Cu" "B.Mask" "B.Paste")
			(roundrect_rratio 0.2)
			(net 4 "1V0_Power")
			(pintype "passive")
		)
	)
)
